# T6G (Grand Teton) — schematic netlist excerpt (pin names and nets, part order shuffled) for the footprints in the layout excerpt that follows; sources: Cadence DE-HDL packaged netlist, KiCad conversion of 04192023_DAF0TMB3IC0_F0TG_MB_C_brd_V02_OCP.brd

R3318  Q_RES  100K 1% EMPTY  pkg 0402LF  page 127 : A = P3V3_AUX ; B = GPU_FPGA_READY
R993  Q_RES  1K 1% CHIP  pkg 0402LF  page 83 : A = FM_SYS_THROTTLE_N ; B = P3V3_AUX

(kicad_pcb
	(version 20260206)
	(generator "pcbnew")
	(generator_version "10.0")
	(general
		(thickness 1.6)
		(legacy_teardrops no)
	)
	(paper "A4")
	(title_block
		(title "04192023_DAF0TMB3IC0_F0TG_MB_C_brd_V02_OCP.brd")
		(comment 1 "Grand Teton / footprints 5027-5028 of 8354")
	)
	(layers
		(0 "F.Cu" signal "TOP")
		(4 "In1.Cu" signal "GND")
		(6 "In2.Cu" signal "IN1")
		(8 "In3.Cu" signal "GND1")
		(10 "In4.Cu" signal "IN2")
		(12 "In5.Cu" signal "GND2")
		(14 "In6.Cu" signal "IN3")
		(16 "In7.Cu" signal "GND3")
		(18 "In8.Cu" signal "VCC")
		(20 "In9.Cu" signal "VCC1")
		(22 "In10.Cu" signal "GND4")
		(24 "In11.Cu" signal "IN4")
		(26 "In12.Cu" signal "GND5")
		(28 "In13.Cu" signal "IN5")
		(30 "In14.Cu" signal "GND6")
		(32 "In15.Cu" signal "IN6")
		(34 "In16.Cu" signal "GND7")
		(2 "B.Cu" signal "BOTTOM")
		(9 "F.Adhes" user "F.Adhesive")
		(11 "B.Adhes" user "B.Adhesive")
		(13 "F.Paste" user "Package Geometry/Pastemask Top")
		(15 "B.Paste" user "Package Geometry/Pastemask Bottom")
		(5 "F.SilkS" user "Ref Des/Silkscreen Top")
		(7 "B.SilkS" user "Ref Des/Silkscreen Bottom")
		(1 "F.Mask" user "Board Geometry/Soldermask Top")
		(3 "B.Mask" user "Board Geometry/Soldermask Bottom")
		(17 "Dwgs.User" user "User.Drawings")
		(19 "Cmts.User" user "User.Comments")
		(21 "Eco1.User" user "User.Eco1")
		(23 "Eco2.User" user "User.Eco2")
		(25 "Edge.Cuts" user "Board Geometry/Outline")
		(27 "Margin" user)
		(31 "F.CrtYd" user "Package Geometry/Place Bound Top")
		(29 "B.CrtYd" user "Package Geometry/Place Bound Bottom")
		(35 "F.Fab" user "Ref Des/Assembly Top")
		(33 "B.Fab" user "Ref Des/Assembly Bottom")
	)
	(footprint ""
		(layer "B.Cu")
		(at 167.116252 -115.28552)
		(property "Reference" "R993"
			(at 0 0 0)
			(layer "B.SilkS")
			(hide yes)
			(effects
				(font
					(size 1.27 1.27)
				)
				(justify mirror)
			)
		)
		(property "Value" ""
			(at 0 0 0)
			(layer "B.Fab")
			(effects
				(font
					(size 1.27 1.27)
				)
				(justify mirror)
			)
		)
		(duplicate_pad_numbers_are_jumpers no)
		(fp_line
			(start -0.7874 -0.4064)
			(end -0.7874 0.4064)
			(stroke
				(width 0.1524)
				(type default)
			)
			(layer "B.SilkS")
		)
		(fp_line
			(start -0.7874 0.4064)
			(end 0.7874 0.4064)
			(stroke
				(width 0.1524)
				(type default)
			)
			(layer "B.SilkS")
		)
		(fp_line
			(start 0.7874 -0.4064)
			(end -0.7874 -0.4064)
			(stroke
				(width 0.1524)
				(type default)
			)
			(layer "B.SilkS")
		)
		(fp_line
			(start 0.7874 0.4064)
			(end 0.7874 -0.4064)
			(stroke
				(width 0.1524)
				(type default)
			)
			(layer "B.SilkS")
		)
		(fp_line
			(start -0.67945 -0.3048)
			(end -0.67945 0.3048)
			(stroke
				(width 0.1)
				(type default)
			)
			(layer "B.Fab")
		)
		(fp_line
			(start -0.67945 0.3048)
			(end -0.120396 0.3048)
			(stroke
				(width 0.1)
				(type default)
			)
			(layer "B.Fab")
		)
		(fp_line
			(start -0.12065 -0.3048)
			(end -0.67945 -0.3048)
			(stroke
				(width 0.1)
				(type default)
			)
			(layer "B.Fab")
		)
		(fp_line
			(start -0.12065 -0.2794)
			(end -0.12065 -0.3048)
			(stroke
				(width 0.1)
				(type default)
			)
			(layer "B.Fab")
		)
		(fp_line
			(start -0.120396 0.2794)
			(end 0.12065 0.2794)
			(stroke
				(width 0.1)
				(type default)
			)
			(layer "B.Fab")
		)
		(fp_line
			(start -0.120396 0.3048)
			(end -0.120396 0.2794)
			(stroke
				(width 0.1)
				(type default)
			)
			(layer "B.Fab")
		)
		(fp_line
			(start 0.12065 -0.305054)
			(end 0.12065 -0.2794)
			(stroke
				(width 0.1)
				(type default)
			)
			(layer "B.Fab")
		)
		(fp_line
			(start 0.12065 -0.2794)
			(end -0.12065 -0.2794)
			(stroke
				(width 0.1)
				(type default)
			)
			(layer "B.Fab")
		)
		(fp_line
			(start 0.12065 0.2794)
			(end 0.12065 0.3048)
			(stroke
				(width 0.1)
				(type default)
			)
			(layer "B.Fab")
		)
		(fp_line
			(start 0.12065 0.3048)
			(end 0.67945 0.3048)
			(stroke
				(width 0.1)
				(type default)
			)
			(layer "B.Fab")
		)
		(fp_line
			(start 0.67945 -0.305054)
			(end 0.12065 -0.305054)
			(stroke
				(width 0.1)
				(type default)
			)
			(layer "B.Fab")
		)
		(fp_line
			(start 0.67945 0.3048)
			(end 0.67945 -0.305054)
			(stroke
				(width 0.1)
				(type default)
			)
			(layer "B.Fab")
		)
		(pad "1" smd circle
			(at 0.40005 0 180)
			(size 0 0)
			(layers "B.Cu" "B.Mask" "B.Paste")
			(net "FM_SYS_THROTTLE_N")
		)
		(pad "2" smd circle
			(at -0.40005 0 180)
			(size 0 0)
			(layers "B.Cu" "B.Mask" "B.Paste")
			(net "P3V3_AUX")
		)
	)
	(footprint ""
		(layer "B.Cu")
		(at 53.09362 -422.777666)
		(property "Reference" "R3318"
			(at 0 0 0)
			(layer "B.SilkS")
			(hide yes)
			(effects
				(font
					(size 1.27 1.27)
				)
				(justify mirror)
			)
		)
		(property "Value" ""
			(at 0 0 0)
			(layer "B.Fab")
			(effects
				(font
					(size 1.27 1.27)
				)
				(justify mirror)
			)
		)
		(duplicate_pad_numbers_are_jumpers no)
		(fp_line
			(start -0.7874 -0.4064)
			(end -0.7874 0.4064)
			(stroke
				(width 0.1524)
				(type default)
			)
			(layer "B.SilkS")
		)
		(fp_line
			(start -0.7874 0.4064)
			(end 0.7874 0.4064)
			(stroke
				(width 0.1524)
				(type default)
			)
			(layer "B.SilkS")
		)
		(fp_line
			(start 0.7874 -0.4064)
			(end -0.7874 -0.4064)
			(stroke
				(width 0.1524)
				(type default)
			)
			(layer "B.SilkS")
		)
		(fp_line
			(start 0.7874 0.4064)
			(end 0.7874 -0.4064)
			(stroke
				(width 0.1524)
				(type default)
			)
			(layer "B.SilkS")
		)
		(fp_line
			(start -0.67945 -0.3048)
			(end -0.67945 0.3048)
			(stroke
				(width 0.1)
				(type default)
			)
			(layer "B.Fab")
		)
		(fp_line
			(start -0.67945 0.3048)
			(end -0.120396 0.3048)
			(stroke
				(width 0.1)
				(type default)
			)
			(layer "B.Fab")
		)
		(fp_line
			(start -0.12065 -0.3048)
			(end -0.67945 -0.3048)
			(stroke
				(width 0.1)
				(type default)
			)
			(layer "B.Fab")
		)
		(fp_line
			(start -0.12065 -0.2794)
			(end -0.12065 -0.3048)
			(stroke
				(width 0.1)
				(type default)
			)
			(layer "B.Fab")
		)
		(fp_line
			(start -0.120396 0.2794)
			(end 0.12065 0.2794)
			(stroke
				(width 0.1)
				(type default)
			)
			(layer "B.Fab")
		)
		(fp_line
			(start -0.120396 0.3048)
			(end -0.120396 0.2794)
			(stroke
				(width 0.1)
				(type default)
			)
			(layer "B.Fab")
		)
		(fp_line
			(start 0.12065 -0.305054)
			(end 0.12065 -0.2794)
			(stroke
				(width 0.1)
				(type default)
			)
			(layer "B.Fab")
		)
		(fp_line
			(start 0.12065 -0.2794)
			(end -0.12065 -0.2794)
			(stroke
				(width 0.1)
				(type default)
			)
			(layer "B.Fab")
		)
		(fp_line
			(start 0.12065 0.2794)
			(end 0.12065 0.3048)
			(stroke
				(width 0.1)
				(type default)
			)
			(layer "B.Fab")
		)
		(fp_line
			(start 0.12065 0.3048)
			(end 0.67945 0.3048)
			(stroke
				(width 0.1)
				(type default)
			)
			(layer "B.Fab")
		)
		(fp_line
			(start 0.67945 -0.305054)
			(end 0.12065 -0.305054)
			(stroke
				(width 0.1)
				(type default)
			)
			(layer "B.Fab")
		)
		(fp_line
			(start 0.67945 0.3048)
			(end 0.67945 -0.305054)
			(stroke
				(width 0.1)
				(type default)
			)
			(layer "B.Fab")
		)
		(pad "1" smd circle
			(at 0.40005 0 180)
			(size 0 0)
			(layers "B.Cu" "B.Mask" "B.Paste")
			(net "P3V3_AUX")
		)
		(pad "2" smd circle
			(at -0.40005 0 180)
			(size 0 0)
			(layers "B.Cu" "B.Mask" "B.Paste")
			(net "GPU_FPGA_READY")
		)
	)
)
